# T6G (Grand Teton) — schematic netlist excerpt (pin names and nets, part order shuffled) for the footprints in the layout excerpt that follows; sources: Cadence DE-HDL packaged netlist, KiCad conversion of 04192023_DAF0TMB3IC0_F0TG_MB_C_brd_V02_OCP.brd

R390  Q_RES  2.2K 5% CHIP  pkg 0402LF  page 27 : A = P3V3_AUX ; B = CPU0_CORETYPE0
R8423  Q_RES  1K 1% CHIP  pkg 0402LF  page 131 : A = SGPIO_OCP_SFF_CLK ; B = P3V3_OCP_SFF

(kicad_pcb
	(version 20260206)
	(generator "pcbnew")
	(generator_version "10.0")
	(general
		(thickness 1.6)
		(legacy_teardrops no)
	)
	(paper "A4")
	(title_block
		(title "04192023_DAF0TMB3IC0_F0TG_MB_C_brd_V02_OCP.brd")
		(comment 1 "Grand Teton / footprints 7703-7704 of 8354")
	)
	(layers
		(0 "F.Cu" signal "TOP")
		(4 "In1.Cu" signal "GND")
		(6 "In2.Cu" signal "IN1")
		(8 "In3.Cu" signal "GND1")
		(10 "In4.Cu" signal "IN2")
		(12 "In5.Cu" signal "GND2")
		(14 "In6.Cu" signal "IN3")
		(16 "In7.Cu" signal "GND3")
		(18 "In8.Cu" signal "VCC")
		(20 "In9.Cu" signal "VCC1")
		(22 "In10.Cu" signal "GND4")
		(24 "In11.Cu" signal "IN4")
		(26 "In12.Cu" signal "GND5")
		(28 "In13.Cu" signal "IN5")
		(30 "In14.Cu" signal "GND6")
		(32 "In15.Cu" signal "IN6")
		(34 "In16.Cu" signal "GND7")
		(2 "B.Cu" signal "BOTTOM")
		(9 "F.Adhes" user "F.Adhesive")
		(11 "B.Adhes" user "B.Adhesive")
		(13 "F.Paste" user "Package Geometry/Pastemask Top")
		(15 "B.Paste" user "Package Geometry/Pastemask Bottom")
		(5 "F.SilkS" user "Ref Des/Silkscreen Top")
		(7 "B.SilkS" user "Ref Des/Silkscreen Bottom")
		(1 "F.Mask" user "Board Geometry/Soldermask Top")
		(3 "B.Mask" user "Board Geometry/Soldermask Bottom")
		(17 "Dwgs.User" user "User.Drawings")
		(19 "Cmts.User" user "User.Comments")
		(21 "Eco1.User" user "User.Eco1")
		(23 "Eco2.User" user "User.Eco2")
		(25 "Edge.Cuts" user "Board Geometry/Outline")
		(27 "Margin" user)
		(31 "F.CrtYd" user "Package Geometry/Place Bound Top")
		(29 "B.CrtYd" user "Package Geometry/Place Bound Bottom")
		(35 "F.Fab" user "Ref Des/Assembly Top")
		(33 "B.Fab" user "Ref Des/Assembly Bottom")
	)
	(footprint ""
		(layer "B.Cu")
		(at 318.306958 -203.917296 -90)
		(property "Reference" "R390"
			(at 0 0 90)
			(layer "B.SilkS")
			(hide yes)
			(effects
				(font
					(size 1.27 1.27)
				)
				(justify mirror)
			)
		)
		(property "Value" ""
			(at 0 0 90)
			(layer "B.Fab")
			(effects
				(font
					(size 1.27 1.27)
				)
				(justify mirror)
			)
		)
		(duplicate_pad_numbers_are_jumpers no)
		(fp_line
			(start -0.7874 0.4064)
			(end 0.7874 0.4064)
			(stroke
				(width 0.1524)
				(type default)
			)
			(layer "B.SilkS")
		)
		(fp_line
			(start 0.7874 0.4064)
			(end 0.7874 -0.4064)
			(stroke
				(width 0.1524)
				(type default)
			)
			(layer "B.SilkS")
		)
		(fp_line
			(start -0.7874 -0.4064)
			(end -0.7874 0.4064)
			(stroke
				(width 0.1524)
				(type default)
			)
			(layer "B.SilkS")
		)
		(fp_line
			(start 0.7874 -0.4064)
			(end -0.7874 -0.4064)
			(stroke
				(width 0.1524)
				(type default)
			)
			(layer "B.SilkS")
		)
		(fp_line
			(start -0.67945 0.3048)
			(end -0.120396 0.3048)
			(stroke
				(width 0.1)
				(type default)
			)
			(layer "B.Fab")
		)
		(fp_line
			(start -0.120396 0.3048)
			(end -0.120396 0.2794)
			(stroke
				(width 0.1)
				(type default)
			)
			(layer "B.Fab")
		)
		(fp_line
			(start 0.12065 0.3048)
			(end 0.67945 0.3048)
			(stroke
				(width 0.1)
				(type default)
			)
			(layer "B.Fab")
		)
		(fp_line
			(start 0.67945 0.3048)
			(end 0.67945 -0.305054)
			(stroke
				(width 0.1)
				(type default)
			)
			(layer "B.Fab")
		)
		(fp_line
			(start -0.120396 0.2794)
			(end 0.12065 0.2794)
			(stroke
				(width 0.1)
				(type default)
			)
			(layer "B.Fab")
		)
		(fp_line
			(start 0.12065 0.2794)
			(end 0.12065 0.3048)
			(stroke
				(width 0.1)
				(type default)
			)
			(layer "B.Fab")
		)
		(fp_line
			(start -0.12065 -0.2794)
			(end -0.12065 -0.3048)
			(stroke
				(width 0.1)
				(type default)
			)
			(layer "B.Fab")
		)
		(fp_line
			(start 0.12065 -0.2794)
			(end -0.12065 -0.2794)
			(stroke
				(width 0.1)
				(type default)
			)
			(layer "B.Fab")
		)
		(fp_line
			(start -0.67945 -0.3048)
			(end -0.67945 0.3048)
			(stroke
				(width 0.1)
				(type default)
			)
			(layer "B.Fab")
		)
		(fp_line
			(start -0.12065 -0.3048)
			(end -0.67945 -0.3048)
			(stroke
				(width 0.1)
				(type default)
			)
			(layer "B.Fab")
		)
		(fp_line
			(start 0.12065 -0.305054)
			(end 0.12065 -0.2794)
			(stroke
				(width 0.1)
				(type default)
			)
			(layer "B.Fab")
		)
		(fp_line
			(start 0.67945 -0.305054)
			(end 0.12065 -0.305054)
			(stroke
				(width 0.1)
				(type default)
			)
			(layer "B.Fab")
		)
		(pad "1" smd circle
			(at 0.40005 0 90)
			(size 0 0)
			(layers "B.Cu" "B.Mask" "B.Paste")
			(net "P3V3_AUX")
		)
		(pad "2" smd circle
			(at -0.40005 0 90)
			(size 0 0)
			(layers "B.Cu" "B.Mask" "B.Paste")
			(net "CPU0_CORETYPE0")
		)
	)
	(footprint ""
		(layer "B.Cu")
		(at 449.5546 -10.594086 90)
		(property "Reference" "R8423"
			(at 0 0 90)
			(layer "B.SilkS")
			(hide yes)
			(effects
				(font
					(size 1.27 1.27)
				)
				(justify mirror)
			)
		)
		(property "Value" ""
			(at 0 0 90)
			(layer "B.Fab")
			(effects
				(font
					(size 1.27 1.27)
				)
				(justify mirror)
			)
		)
		(duplicate_pad_numbers_are_jumpers no)
		(fp_line
			(start 0.7874 -0.4064)
			(end -0.7874 -0.4064)
			(stroke
				(width 0.1524)
				(type default)
			)
			(layer "B.SilkS")
		)
		(fp_line
			(start -0.7874 -0.4064)
			(end -0.7874 0.4064)
			(stroke
				(width 0.1524)
				(type default)
			)
			(layer "B.SilkS")
		)
		(fp_line
			(start 0.7874 0.4064)
			(end 0.7874 -0.4064)
			(stroke
				(width 0.1524)
				(type default)
			)
			(layer "B.SilkS")
		)
		(fp_line
			(start -0.7874 0.4064)
			(end 0.7874 0.4064)
			(stroke
				(width 0.1524)
				(type default)
			)
			(layer "B.SilkS")
		)
		(fp_line
			(start 0.67945 -0.305054)
			(end 0.12065 -0.305054)
			(stroke
				(width 0.1)
				(type default)
			)
			(layer "B.Fab")
		)
		(fp_line
			(start 0.12065 -0.305054)
			(end 0.12065 -0.2794)
			(stroke
				(width 0.1)
				(type default)
			)
			(layer "B.Fab")
		)
		(fp_line
			(start -0.12065 -0.3048)
			(end -0.67945 -0.3048)
			(stroke
				(width 0.1)
				(type default)
			)
			(layer "B.Fab")
		)
		(fp_line
			(start -0.67945 -0.3048)
			(end -0.67945 0.3048)
			(stroke
				(width 0.1)
				(type default)
			)
			(layer "B.Fab")
		)
		(fp_line
			(start 0.12065 -0.2794)
			(end -0.12065 -0.2794)
			(stroke
				(width 0.1)
				(type default)
			)
			(layer "B.Fab")
		)
		(fp_line
			(start -0.12065 -0.2794)
			(end -0.12065 -0.3048)
			(stroke
				(width 0.1)
				(type default)
			)
			(layer "B.Fab")
		)
		(fp_line
			(start 0.12065 0.2794)
			(end 0.12065 0.3048)
			(stroke
				(width 0.1)
				(type default)
			)
			(layer "B.Fab")
		)
		(fp_line
			(start -0.120396 0.2794)
			(end 0.12065 0.2794)
			(stroke
				(width 0.1)
				(type default)
			)
			(layer "B.Fab")
		)
		(fp_line
			(start 0.67945 0.3048)
			(end 0.67945 -0.305054)
			(stroke
				(width 0.1)
				(type default)
			)
			(layer "B.Fab")
		)
		(fp_line
			(start 0.12065 0.3048)
			(end 0.67945 0.3048)
			(stroke
				(width 0.1)
				(type default)
			)
			(layer "B.Fab")
		)
		(fp_line
			(start -0.120396 0.3048)
			(end -0.120396 0.2794)
			(stroke
				(width 0.1)
				(type default)
			)
			(layer "B.Fab")
		)
		(fp_line
			(start -0.67945 0.3048)
			(end -0.120396 0.3048)
			(stroke
				(width 0.1)
				(type default)
			)
			(layer "B.Fab")
		)
		(pad "1" smd circle
			(at 0.40005 0 270)
			(size 0 0)
			(layers "B.Cu" "B.Mask" "B.Paste")
			(net "SGPIO_OCP_SFF_CLK")
		)
		(pad "2" smd circle
			(at -0.40005 0 270)
			(size 0 0)
			(layers "B.Cu" "B.Mask" "B.Paste")
			(net "P3V3_OCP_SFF")
		)
	)
)
